# S9S_MB_2U (Grand Teton) — schematic netlist excerpt (pin names and nets, part order shuffled) for the footprints in the layout excerpt that follows; sources: Cadence DE-HDL packaged netlist, KiCad conversion of 03242023_DA0F0TMBIJ0_F0T_Motherboard_J_brd_V01_OCP.brd

C2313  Q_CAP  10UF 6.3V 20% EMPTY  pkg C0402  page 196 : A = P3V3_AUX_USB_HUB_2 ; B = GND

(kicad_pcb
	(version 20260206)
	(generator "pcbnew")
	(generator_version "10.0")
	(general
		(thickness 1.6)
		(legacy_teardrops no)
	)
	(paper "A4")
	(title_block
		(title "03242023_DA0F0TMBIJ0_F0T_Motherboard_J_brd_V01_OCP.brd")
		(comment 1 "Grand Teton / footprints 4378-4378 of 6105")
	)
	(layers
		(0 "F.Cu" signal "TOP")
		(4 "In1.Cu" signal "GND")
		(6 "In2.Cu" signal "IN1")
		(8 "In3.Cu" signal "GND1")
		(10 "In4.Cu" signal "IN2")
		(12 "In5.Cu" signal "GND2")
		(14 "In6.Cu" signal "IN3")
		(16 "In7.Cu" signal "GND3")
		(18 "In8.Cu" signal "VCC")
		(20 "In9.Cu" signal "VCC1")
		(22 "In10.Cu" signal "GND4")
		(24 "In11.Cu" signal "IN4")
		(26 "In12.Cu" signal "GND5")
		(28 "In13.Cu" signal "IN5")
		(30 "In14.Cu" signal "GND6")
		(32 "In15.Cu" signal "IN6")
		(34 "In16.Cu" signal "GND7")
		(2 "B.Cu" signal "BOTTOM")
		(9 "F.Adhes" user "F.Adhesive")
		(11 "B.Adhes" user "B.Adhesive")
		(13 "F.Paste" user "Package Geometry/Pastemask Top")
		(15 "B.Paste" user "Package Geometry/Pastemask Bottom")
		(5 "F.SilkS" user "Ref Des/Silkscreen Top")
		(7 "B.SilkS" user "Ref Des/Silkscreen Bottom")
		(1 "F.Mask" user "Board Geometry/Soldermask Top")
		(3 "B.Mask" user "Board Geometry/Soldermask Bottom")
		(17 "Dwgs.User" user "User.Drawings")
		(19 "Cmts.User" user "User.Comments")
		(21 "Eco1.User" user "User.Eco1")
		(23 "Eco2.User" user "User.Eco2")
		(25 "Edge.Cuts" user "Board Geometry/Outline")
		(27 "Margin" user)
		(31 "F.CrtYd" user "Package Geometry/Place Bound Top")
		(29 "B.CrtYd" user "Package Geometry/Place Bound Bottom")
		(35 "F.Fab" user "Ref Des/Assembly Top")
		(33 "B.Fab" user "Ref Des/Assembly Bottom")
	)
	(footprint ""
		(layer "B.Cu")
		(at 159.766508 -41.805098 -90)
		(property "Reference" "C2313"
			(at 0 0 90)
			(layer "B.SilkS")
			(hide yes)
			(effects
				(font
					(size 1.27 1.27)
				)
				(justify mirror)
			)
		)
		(property "Value" ""
			(at 0 0 90)
			(layer "B.Fab")
			(effects
				(font
					(size 1.27 1.27)
				)
				(justify mirror)
			)
		)
		(duplicate_pad_numbers_are_jumpers no)
		(fp_line
			(start -0.7874 0.4064)
			(end 0.7874 0.4064)
			(stroke
				(width 0.1524)
				(type default)
			)
			(layer "B.SilkS")
		)
		(fp_line
			(start 0.7874 0.4064)
			(end 0.7874 -0.4064)
			(stroke
				(width 0.1524)
				(type default)
			)
			(layer "B.SilkS")
		)
		(fp_line
			(start -0.7874 -0.4064)
			(end -0.7874 0.4064)
			(stroke
				(width 0.1524)
				(type default)
			)
			(layer "B.SilkS")
		)
		(fp_line
			(start 0.7874 -0.4064)
			(end -0.7874 -0.4064)
			(stroke
				(width 0.1524)
				(type default)
			)
			(layer "B.SilkS")
		)
		(fp_line
			(start -0.67945 0.3048)
			(end -0.120396 0.3048)
			(stroke
				(width 0.1)
				(type default)
			)
			(layer "B.Fab")
		)
		(fp_line
			(start -0.120396 0.3048)
			(end -0.120396 0.2794)
			(stroke
				(width 0.1)
				(type default)
			)
			(layer "B.Fab")
		)
		(fp_line
			(start 0.12065 0.3048)
			(end 0.67945 0.3048)
			(stroke
				(width 0.1)
				(type default)
			)
			(layer "B.Fab")
		)
		(fp_line
			(start 0.67945 0.3048)
			(end 0.67945 -0.305054)
			(stroke
				(width 0.1)
				(type default)
			)
			(layer "B.Fab")
		)
		(fp_line
			(start -0.120396 0.2794)
			(end 0.12065 0.2794)
			(stroke
				(width 0.1)
				(type default)
			)
			(layer "B.Fab")
		)
		(fp_line
			(start 0.12065 0.2794)
			(end 0.12065 0.3048)
			(stroke
				(width 0.1)
				(type default)
			)
			(layer "B.Fab")
		)
		(fp_line
			(start -0.12065 -0.2794)
			(end -0.12065 -0.3048)
			(stroke
				(width 0.1)
				(type default)
			)
			(layer "B.Fab")
		)
		(fp_line
			(start 0.12065 -0.2794)
			(end -0.12065 -0.2794)
			(stroke
				(width 0.1)
				(type default)
			)
			(layer "B.Fab")
		)
		(fp_line
			(start -0.67945 -0.3048)
			(end -0.67945 0.3048)
			(stroke
				(width 0.1)
				(type default)
			)
			(layer "B.Fab")
		)
		(fp_line
			(start -0.12065 -0.3048)
			(end -0.67945 -0.3048)
			(stroke
				(width 0.1)
				(type default)
			)
			(layer "B.Fab")
		)
		(fp_line
			(start 0.12065 -0.305054)
			(end 0.12065 -0.2794)
			(stroke
				(width 0.1)
				(type default)
			)
			(layer "B.Fab")
		)
		(fp_line
			(start 0.67945 -0.305054)
			(end 0.12065 -0.305054)
			(stroke
				(width 0.1)
				(type default)
			)
			(layer "B.Fab")
		)
		(pad "1" smd circle
			(at 0.40005 0 90)
			(size 0 0)
			(layers "B.Cu" "B.Mask" "B.Paste")
			(net "P3V3_AUX_USB_HUB_2")
		)
		(pad "2" smd circle
			(at -0.40005 0 90)
			(size 0 0)
			(layers "B.Cu" "B.Mask" "B.Paste")
			(net "GND")
		)
	)
)
